# BOM.xlsx — Sheet1 (bom)
| Index | Quantity | Part Number | Manufacturer Part Number | Description | Customer Reference | Available | Backorder | Unit Price | Extended Price USD |
| 1 | 4 | 399-1091-1-ND | C0603C103K5RACTU | CAP CER 10000PF 50V X7R 0603 | TIME CARD - C3, C4, C67, C76 | 4 | 0 | 0.10000 | 0.40 |
| 2 | 1 | 609-5379-1-ND | 10118192-0002LF | CONN RCPT USB2.0 MICRO B SMD R/A | TIME CARD - J2 | 1 | 0 | 0.42000 | 0.42 |
| 3 | 1 | P4.70KHCT-ND | ERJ-3EKF4701V | RES SMD 4.7K OHM 1% 1/10W 0603 | TIME CARD - R22 | 1 | 0 | 0.10000 | 0.10 |
| 4 | 1 | P26.1KHCT-ND | ERJ-3EKF2612V | RES SMD 26.1K OHM 1% 1/10W 0603 | TIME CARD - R5 | 1 | 0 | 0.10000 | 0.10 |
| 5 | 4 | A118077CT-ND | 1909763-1 | CONN UMCC JACK STR 50OHM SMD | TIME CARD - AN5, AN6, AN7, AN8 | 4 | 0 | 0.46000 | 1.84 |
| 6 | 11 | P0.0JCT-ND | ERJ-2GE0R00X | RES SMD 0 OHM JUMPER 1/10W 0402 | TIME CARD - R[10-16, R32, R17, R23, R24 | 11 | 0 | 0.01900 | 0.21 |
| 7 | 4 | 255-3246-1-ND | AXK680347YG | CONN HDR 80POS SMD GOLD | TIME CARD - P1A, P1B, P1C, P1D | 4 | 0 | 2.88000 | 11.52 |
| 8 | 4 | ARFX1232-ND | 901-143-6RFX | CONN SMA JACK R/A 50 OHM PCB | TIME CARD - AN1, AN2, AN3, AN4 | 4 | 0 | 7.94000 | 31.76 |
| 9 | 2 | 399-5089-1-ND | C0603C104K5RACTU | CAP CER 0.1UF 50V X7R 0603 | TIME CARD - C19, C21 | 2 | 0 | 0.12000 | 0.24 |
| 10 | 15 | 490-12323-6-ND | GRT188R61E106ME13D | CAP CER 10UF 25V X5R 0603 | TIME CARD-C[5-8,1,13,14,55,56,58,60,62,87,89,92] | 15 | 0 | 0.81667 | 12.25 |
| 11 | 2 | 587-2985-1-ND | TMK212BBJ106KG-T | CAP CER 10UF 25V X5R 0805 | TIME CARD - C55, C92 | 2 | 0 | 0.20000 | 0.40 |
| 12 | 2 | 445-12207-1-ND | CGA2B3X5R1H333K050BB | CAP CER 0.033UF 50V X5R 0402 | TIME CARD - C20, C22 | 2 | 0 | 0.10000 | 0.20 |
| 13 | 4 | 490-9952-1-ND | GRM219R61C226ME15L | CAP CER 22UF 16V X5R 0805 | TIME CARD - C72, C73, C74, C75 | 4 | 0 | 0.52000 | 2.08 |
| 14 | 2 | 399-1053-1-ND | C0603C220J5GACTU | CAP CER 22PF 50V C0G/NP0 0603 | TIME CARD - C85, C86 | 2 | 0 | 0.15000 | 0.30 |
| 15 | 4 | SMCJ6.5CALFCT-ND | SMCJ6.5CA | TVS DIODE 6.5V 11.2V DO214AB | TIME CARD - D15, D16, D17, D18 | 4 | 0 | 0.61000 | 2.44 |
| 16 | 1 | CP-002A-ND | PJ-002A | CONN PWR JACK 2X5.5MM SOLDER | TIME CARD - J1 | 1 | 0 | 0.60000 | 0.60 |
| 17 | 2 | 445-1565-1-ND | MPZ1608S221ATA00 | FERRITE BEAD 220 OHM 0603 1LN | TIME CARD - FB2, FB3 | 2 | 0 | 0.10000 | 0.20 |
| 18 | 4 | BAT54SWQ-7-FDICT-ND | BAT54SWQ-7-F | DIODE ARRAY SCHOTTKY 30V SOT323 | TIME CARD - D5, D6, D7, D8 | 4 | 0 | 0.32000 | 1.28 |
| 19 | 1 | SF-0603S200-2CT-ND | SF-0603S200-2 | FUSE BOARD MOUNT 2A 32VDC 0603 | TIME CARD - F1 | 1 | 0 | 0.80000 | 0.80 |
| 20 | 1 | A31727CT-ND | 1734035-2 | CONN RCPT USB2.0 MINI B SMD R/A | TIME CARD - J3 | 1 | 0 | 1.66000 | 1.66 |
| 21 | 4 | 541-33.0CCT-ND | CRCW080533R0FKEA | RES SMD 33 OHM 1% 1/8W 0805 | TIME CARD - R18, R19, R20, R21 | 4 | 0 | 0.10000 | 0.40 |
| 22 | 2 | P2.20KHCT-ND | ERJ-3EKF2201V | RES SMD 2.2K OHM 1% 1/10W 0603 | TIME CARD - R8, R9 | 2 | 0 | 0.10000 | 0.20 |
| 23 | 1 | CKC5106-ND | L101011MS02Q | SWITCH SLIDE SPST 4A 125V | TIME CARD - SW1 | 1 | 0 | 1.83000 | 1.83 |
| 24 | 2 | SW1020CT-ND | B3U-1000P | SWITCH TACTILE SPST-NO 0.05A 12V | TIME CARD - S5, S6 | 2 | 0 | 0.92000 | 1.84 |
| 25 | 1 | 1888-1000-1-ND | BNO080 | IMU ACCEL/GYRO/MAG I2C 32BIT | TIME CARD - U8 | 1 | 0 | 12.26000 | 12.26 |
| 26 | 1 | WM24007CT-ND | 0529910208 | CONN RCPT 20POS SMD GOLD | TIME CARD - U10B | 1 | 0 | 1.28000 | 1.28 |
| 27 | 2 | 768-1135-1-ND | FT230XS-R | IC USB SERIAL BASIC UART 16SSOP | TIME CARD - U6, U16 | 2 | 0 | 2.04000 | 4.08 |
| 28 | 2 | P1.00KHCT-ND | ERJ-3EKF1001V | RES SMD 1K OHM 1% 1/10W 0603 | TIME CARD - R34, R35 | 2 | 0 | 0.10000 | 0.20 |
| 29 | 2 | 1589-1524-1-ND | MP1482DS-LF-Z | IC REG BUCK ADJUSTABLE 2A 8SOIC | TIME CARD - U1, U2 | 2 | 0 | 2.92000 | 5.84 |
| 30 | 1 | SAM14025CT-ND | HTST-105-01-L-DV-A-P-TR | CONN HEADER SMD 10POS 2.54MM | TIME CARD - U5 | 1 | 0 | 3.45000 | 3.45 |
| 31 | 2 | 672-RCB-F9T-ND | RCB-F9T | ZED-F9T TIMING BOARD | TIME CARD - GPS1, GPS2 | 2 | 0 | 278.44000 | 556.88 |
| 32 | 2 | SAM11876-ND | SQW-104-01-F-D-VS | CONN RCPT 8POS 0.079 GOLD SMD | TIME CARD - U9, U14 | 2 | 0 | 1.62000 | 3.24 |
| 33 | 2 | SRR1240-100MCT-ND | SRR1240-100M | FIXED IND 10UH 4A 32 MOHM SMD | TIME CARD - L1, L2 | 2 | 0 | 1.09000 | 2.18 |
| 34 | 2 | WM10869-ND | 0455580003 | CONN HEADER R/A 6POS 4.2MM | TIME CARD - J2 | 2 | 0 | 0.85000 | 1.70 |
| 35 | 4 | 399-15436-1-ND | C0805C105K5PAC7800 | CAP CER 1UF 50V X5R 0805 | TIME CARD - C54, C91, C65, C84 | 4 | 0 | 0.35000 | 1.40 |
| 36 | 1 | 535-10241-1-ND | ABS25-32.768KHZ-6-1-T | CRYSTAL 32.7680KHZ 6PF SMD | TIME CARD - X1 | 1 | 0 | 0.67000 | 0.67 |
| 37 | 3 | NRVTS245ESFT1GOSCT-ND | NRVTS245ESFT1G | DIODE SCHOTTKY 45V 2A SOD123FL | TIME CARD - D1, D2, D3 | 3 | 0 | 0.33000 | 0.99 |
| 38 | 1 | 732-12325-1-ND | 79527141 | BATTERY HOLDER COIN 20MM SMD | TIME CARD - BT1 | 1 | 0 | 1.86000 | 1.86 |
| 39 | 1 | 828-1079-1-ND | BMP388 | SENSOR PRESSURE ABS | TIME CARD - IC? | 1 | 0 | 3.47000 | 3.47 |
| 40 | 2 | SAM1038-03-ND | TSW-103-08-G-S | CONN HEADER VERT 3POS 2.54MM | TIME CARD - JP1, JP2 | 2 | 0 | 0.39000 | 0.78 |
| 41 | 1 | DS3231SN#T&RCT-ND | DS3231SN#T&R | IC RTC CLK/CALENDAR I2C 16-SOIC | TIME CARD - U5 | 1 | 0 | 8.82000 | 8.82 |
| 42 | 31 | 445-6899-1-ND | CGA2B3X7R1H104K050BB | CAP CER 0.1UF 50V X7R 0402 | C[2,9,10-12,15-18,44-53,77-83,57,59,61,63,88,90] | 31 | 0 | 0.10700 | 3.32 |
| 43 | 7 | 67-1548-1-ND | SML-LX0603IW-TR | LED RED DIFFUSED SMD | TIME CARD - D4, D9, D10, D11, D12, D13, D14 | 7 | 0 | 0.36000 | 2.52 |
| 44 | 5 | P200HCT-ND | ERJ-3EKF2000V | RES SMD 200 OHM 1% 1/10W 0603 | TIME CARD - R1, R28, R29, R30, R31 | 5 | 0 | 0.10000 | 0.50 |
| 45 | 7 | P10.0KHCT-ND | ERJ-3EKF1002V | RES SMD 10K OHM 1% 1/10W 0603 | TIME CARD - R6, R7, R27, R32, R33, R42, R43 | 7 | 0 | 0.10000 | 0.70 |
| 46 | 2 | P499LCT-ND | ERJ-2RKF4990X | RES SMD 499 OHM 1% 1/10W 0402 | TIME CARD - R25, R26 | 2 | 0 | 0.10000 | 0.20 |
| 47 | 3 | P47.0KHCT-ND | ERJ-3EKF4702V | RES SMD 47K OHM 1% 1/10W 0603 | TIME CARD -  R2, R3, R4 | 3 | 0 | 0.10000 | 0.30 |
